(kicad_pcb
	(version 20260206)
	(generator "pcbnew")
	(generator_version "10.0")
	(general
		(thickness 1.6)
		(legacy_teardrops no)
	)
	(paper "A4")
	(title_block
		(title "04192023_DAF0TMB3IC0_F0TG_MB_C_brd_V02_OCP.brd")
		(comment 1 "Grand Teton / footprints 726-731 of 8354")
	)
	(layers
		(0 "F.Cu" signal "TOP")
		(4 "In1.Cu" signal "GND")
		(6 "In2.Cu" signal "IN1")
		(8 "In3.Cu" signal "GND1")
		(10 "In4.Cu" signal "IN2")
		(12 "In5.Cu" signal "GND2")
		(14 "In6.Cu" signal "IN3")
		(16 "In7.Cu" signal "GND3")
		(18 "In8.Cu" signal "VCC")
		(20 "In9.Cu" signal "VCC1")
		(22 "In10.Cu" signal "GND4")
		(24 "In11.Cu" signal "IN4")
		(26 "In12.Cu" signal "GND5")
		(28 "In13.Cu" signal "IN5")
		(30 "In14.Cu" signal "GND6")
		(32 "In15.Cu" signal "IN6")
		(34 "In16.Cu" signal "GND7")
		(2 "B.Cu" signal "BOTTOM")
		(9 "F.Adhes" user "F.Adhesive")
		(11 "B.Adhes" user "B.Adhesive")
		(13 "F.Paste" user "Package Geometry/Pastemask Top")
		(15 "B.Paste" user "Package Geometry/Pastemask Bottom")
		(5 "F.SilkS" user "Ref Des/Silkscreen Top")
		(7 "B.SilkS" user "Ref Des/Silkscreen Bottom")
		(1 "F.Mask" user "Board Geometry/Soldermask Top")
		(3 "B.Mask" user "Board Geometry/Soldermask Bottom")
		(17 "Dwgs.User" user "User.Drawings")
		(19 "Cmts.User" user "User.Comments")
		(21 "Eco1.User" user "User.Eco1")
		(23 "Eco2.User" user "User.Eco2")
		(25 "Edge.Cuts" user "Board Geometry/Outline")
		(27 "Margin" user)
		(31 "F.CrtYd" user "Package Geometry/Place Bound Top")
		(29 "B.CrtYd" user "Package Geometry/Place Bound Bottom")
		(35 "F.Fab" user "Ref Des/Assembly Top")
		(33 "B.Fab" user "Ref Des/Assembly Bottom")
	)
	(footprint ""
		(layer "F.Cu")
		(at 19.558 -366.649 90)
		(property "Reference" "PQ12"
			(at -1.464818 -3.07594 90)
			(unlocked yes)
			(layer "F.SilkS")
			(effects
				(font
					(size 0.7874 0.5842)
					(thickness 0.1524)
				)
				(justify left)
			)
		)
		(property "Value" ""
			(at 0 0 90)
			(layer "F.Fab")
			(effects
				(font
					(size 1.27 1.27)
				)
			)
		)
		(duplicate_pad_numbers_are_jumpers no)
		(fp_line
			(start 1.603248 -1.500124)
			(end 1.603248 1.500124)
			(stroke
				(width 0.1524)
				(type default)
			)
			(layer "F.SilkS")
		)
		(fp_line
			(start -1.603248 -1.500124)
			(end 1.603248 -1.500124)
			(stroke
				(width 0.1524)
				(type default)
			)
			(layer "F.SilkS")
		)
		(fp_line
			(start 1.603248 1.500124)
			(end -1.603248 1.500124)
			(stroke
				(width 0.1524)
				(type default)
			)
			(layer "F.SilkS")
		)
		(fp_line
			(start -1.603248 1.500124)
			(end -1.603248 -1.500124)
			(stroke
				(width 0.1524)
				(type default)
			)
			(layer "F.SilkS")
		)
		(fp_line
			(start 0.700024 -1.500124)
			(end -0.700024 -1.500124)
			(stroke
				(width 0.1)
				(type default)
			)
			(layer "F.Fab")
		)
		(fp_line
			(start -0.700024 -1.500124)
			(end -0.700024 -1.169924)
			(stroke
				(width 0.1)
				(type default)
			)
			(layer "F.Fab")
		)
		(fp_line
			(start -0.700024 -1.169924)
			(end -1.249934 -1.169924)
			(stroke
				(width 0.1)
				(type default)
			)
			(layer "F.Fab")
		)
		(fp_line
			(start -1.249934 -1.169924)
			(end -1.249934 -0.729996)
			(stroke
				(width 0.1)
				(type default)
			)
			(layer "F.Fab")
		)
		(fp_line
			(start -0.6985 -0.729996)
			(end -0.6985 0.729996)
			(stroke
				(width 0.1)
				(type default)
			)
			(layer "F.Fab")
		)
		(fp_line
			(start -1.249934 -0.729996)
			(end -0.6985 -0.729996)
			(stroke
				(width 0.1)
				(type default)
			)
			(layer "F.Fab")
		)
		(fp_line
			(start 1.249934 -0.219964)
			(end 0.700024 -0.219964)
			(stroke
				(width 0.1)
				(type default)
			)
			(layer "F.Fab")
		)
		(fp_line
			(start 0.700024 -0.219964)
			(end 0.700024 -1.500124)
			(stroke
				(width 0.1)
				(type default)
			)
			(layer "F.Fab")
		)
		(fp_line
			(start 1.249934 0.219964)
			(end 1.249934 -0.219964)
			(stroke
				(width 0.1)
				(type default)
			)
			(layer "F.Fab")
		)
		(fp_line
			(start 0.700024 0.219964)
			(end 1.249934 0.219964)
			(stroke
				(width 0.1)
				(type default)
			)
			(layer "F.Fab")
		)
		(fp_line
			(start -0.6985 0.729996)
			(end -1.249934 0.729996)
			(stroke
				(width 0.1)
				(type default)
			)
			(layer "F.Fab")
		)
		(fp_line
			(start -1.249934 0.729996)
			(end -1.249934 1.169924)
			(stroke
				(width 0.1)
				(type default)
			)
			(layer "F.Fab")
		)
		(fp_line
			(start -0.700024 1.169924)
			(end -0.700024 1.500124)
			(stroke
				(width 0.1)
				(type default)
			)
			(layer "F.Fab")
		)
		(fp_line
			(start -1.249934 1.169924)
			(end -0.700024 1.169924)
			(stroke
				(width 0.1)
				(type default)
			)
			(layer "F.Fab")
		)
		(fp_line
			(start 0.700024 1.500124)
			(end 0.700024 0.219964)
			(stroke
				(width 0.1)
				(type default)
			)
			(layer "F.Fab")
		)
		(fp_line
			(start -0.700024 1.500124)
			(end 0.700024 1.500124)
			(stroke
				(width 0.1)
				(type default)
			)
			(layer "F.Fab")
		)
		(fp_rect
			(start -0.700024 1.500124)
			(end 0.700024 -1.500124)
			(stroke
				(width 0)
				(type default)
			)
			(fill no)
			(layer "F.Fab")
		)
		(pad "D" smd rect
			(at 0.999998 0)
			(size 0.8128 0.9144)
			(layers "F.Cu" "F.Mask" "F.Paste")
			(net "PVDDCR_CPU1_P1_EN1_ADDR_CFG")
		)
		(pad "G" smd rect
			(at -0.999998 -0.94996)
			(size 0.8128 0.9144)
			(layers "F.Cu" "F.Mask" "F.Paste")
			(net "PVDDIO_P1_EN_G")
		)
		(pad "S" smd rect
			(at -0.999998 0.94996)
			(size 0.8128 0.9144)
			(layers "F.Cu" "F.Mask" "F.Paste")
			(net "P3V3_AUX")
		)
	)
	(footprint ""
		(layer "F.Cu")
		(at 360.366056 -256.012188 90)
		(property "Reference" "C3927"
			(at 0 0 90)
			(layer "F.SilkS")
			(hide yes)
			(effects
				(font
					(size 1.27 1.27)
				)
			)
		)
		(property "Value" ""
			(at 0 0 90)
			(layer "F.Fab")
			(effects
				(font
					(size 1.27 1.27)
				)
			)
		)
		(duplicate_pad_numbers_are_jumpers no)
		(fp_line
			(start 0.7874 -0.4064)
			(end 0.7874 0.4064)
			(stroke
				(width 0.1524)
				(type default)
			)
			(layer "F.SilkS")
		)
		(fp_line
			(start -0.7874 -0.4064)
			(end 0.7874 -0.4064)
			(stroke
				(width 0.1524)
				(type default)
			)
			(layer "F.SilkS")
		)
		(fp_line
			(start 0.7874 0.4064)
			(end -0.7874 0.4064)
			(stroke
				(width 0.1524)
				(type default)
			)
			(layer "F.SilkS")
		)
		(fp_line
			(start -0.7874 0.4064)
			(end -0.7874 -0.4064)
			(stroke
				(width 0.1524)
				(type default)
			)
			(layer "F.SilkS")
		)
		(fp_line
			(start -0.12065 -0.305054)
			(end -0.12065 -0.2794)
			(stroke
				(width 0.1)
				(type default)
			)
			(layer "F.Fab")
		)
		(fp_line
			(start -0.67945 -0.305054)
			(end -0.12065 -0.305054)
			(stroke
				(width 0.1)
				(type default)
			)
			(layer "F.Fab")
		)
		(fp_line
			(start 0.67945 -0.3048)
			(end 0.67945 0.3048)
			(stroke
				(width 0.1)
				(type default)
			)
			(layer "F.Fab")
		)
		(fp_line
			(start 0.12065 -0.3048)
			(end 0.67945 -0.3048)
			(stroke
				(width 0.1)
				(type default)
			)
			(layer "F.Fab")
		)
		(fp_line
			(start 0.12065 -0.2794)
			(end 0.12065 -0.3048)
			(stroke
				(width 0.1)
				(type default)
			)
			(layer "F.Fab")
		)
		(fp_line
			(start -0.12065 -0.2794)
			(end 0.12065 -0.2794)
			(stroke
				(width 0.1)
				(type default)
			)
			(layer "F.Fab")
		)
		(fp_line
			(start 0.120396 0.2794)
			(end -0.12065 0.2794)
			(stroke
				(width 0.1)
				(type default)
			)
			(layer "F.Fab")
		)
		(fp_line
			(start -0.12065 0.2794)
			(end -0.12065 0.3048)
			(stroke
				(width 0.1)
				(type default)
			)
			(layer "F.Fab")
		)
		(fp_line
			(start 0.67945 0.3048)
			(end 0.120396 0.3048)
			(stroke
				(width 0.1)
				(type default)
			)
			(layer "F.Fab")
		)
		(fp_line
			(start 0.120396 0.3048)
			(end 0.120396 0.2794)
			(stroke
				(width 0.1)
				(type default)
			)
			(layer "F.Fab")
		)
		(fp_line
			(start -0.12065 0.3048)
			(end -0.67945 0.3048)
			(stroke
				(width 0.1)
				(type default)
			)
			(layer "F.Fab")
		)
		(fp_line
			(start -0.67945 0.3048)
			(end -0.67945 -0.305054)
			(stroke
				(width 0.1)
				(type default)
			)
			(layer "F.Fab")
		)
		(pad "1" smd circle
			(at -0.40005 0 90)
			(size 0 0)
			(layers "F.Cu" "F.Mask" "F.Paste")
			(net "PVDDCR_SOC_P0")
		)
		(pad "2" smd circle
			(at 0.40005 0 90)
			(size 0 0)
			(layers "F.Cu" "F.Mask" "F.Paste")
			(net "GND")
		)
	)
	(footprint ""
		(layer "F.Cu")
		(at 58.305954 -370.57203 -90)
		(property "Reference" "C819"
			(at 0 0 270)
			(layer "F.SilkS")
			(hide yes)
			(effects
				(font
					(size 1.27 1.27)
				)
			)
		)
		(property "Value" ""
			(at 0 0 270)
			(layer "F.Fab")
			(effects
				(font
					(size 1.27 1.27)
				)
			)
		)
		(duplicate_pad_numbers_are_jumpers no)
		(fp_line
			(start -0.299974 0.150114)
			(end -0.299974 -0.150114)
			(stroke
				(width 0.1)
				(type default)
			)
			(layer "F.Fab")
		)
		(fp_line
			(start 0.299974 0.150114)
			(end -0.299974 0.150114)
			(stroke
				(width 0.1)
				(type default)
			)
			(layer "F.Fab")
		)
		(fp_line
			(start -0.299974 -0.150114)
			(end 0.299974 -0.150114)
			(stroke
				(width 0.1)
				(type default)
			)
			(layer "F.Fab")
		)
		(fp_line
			(start 0.299974 -0.150114)
			(end 0.299974 0.150114)
			(stroke
				(width 0.1)
				(type default)
			)
			(layer "F.Fab")
		)
		(pad "1" smd rect
			(at -0.2667 0 270)
			(size 0.3048 0.381)
			(layers "F.Cu" "F.Mask" "F.Paste")
			(net "P5E_CPU1_P0_TX_C_DP<9>")
		)
		(pad "2" smd rect
			(at 0.2667 0 270)
			(size 0.3048 0.381)
			(layers "F.Cu" "F.Mask" "F.Paste")
			(net "P5E_CPU1_P0_TX_DP<9>")
		)
	)
	(footprint ""
		(layer "F.Cu")
		(at 218.130882 -57.399682 -90)
		(property "Reference" "C2071"
			(at 0 0 270)
			(layer "F.SilkS")
			(hide yes)
			(effects
				(font
					(size 1.27 1.27)
				)
			)
		)
		(property "Value" ""
			(at 0 0 270)
			(layer "F.Fab")
			(effects
				(font
					(size 1.27 1.27)
				)
			)
		)
		(duplicate_pad_numbers_are_jumpers no)
		(fp_line
			(start -0.7874 0.4064)
			(end -0.7874 -0.4064)
			(stroke
				(width 0.1524)
				(type default)
			)
			(layer "F.SilkS")
		)
		(fp_line
			(start 0.7874 0.4064)
			(end -0.7874 0.4064)
			(stroke
				(width 0.1524)
				(type default)
			)
			(layer "F.SilkS")
		)
		(fp_line
			(start -0.7874 -0.4064)
			(end 0.7874 -0.4064)
			(stroke
				(width 0.1524)
				(type default)
			)
			(layer "F.SilkS")
		)
		(fp_line
			(start 0.7874 -0.4064)
			(end 0.7874 0.4064)
			(stroke
				(width 0.1524)
				(type default)
			)
			(layer "F.SilkS")
		)
		(fp_line
			(start -0.67945 0.3048)
			(end -0.67945 -0.305054)
			(stroke
				(width 0.1)
				(type default)
			)
			(layer "F.Fab")
		)
		(fp_line
			(start -0.12065 0.3048)
			(end -0.67945 0.3048)
			(stroke
				(width 0.1)
				(type default)
			)
			(layer "F.Fab")
		)
		(fp_line
			(start 0.120396 0.3048)
			(end 0.120396 0.2794)
			(stroke
				(width 0.1)
				(type default)
			)
			(layer "F.Fab")
		)
		(fp_line
			(start 0.67945 0.3048)
			(end 0.120396 0.3048)
			(stroke
				(width 0.1)
				(type default)
			)
			(layer "F.Fab")
		)
		(fp_line
			(start -0.12065 0.2794)
			(end -0.12065 0.3048)
			(stroke
				(width 0.1)
				(type default)
			)
			(layer "F.Fab")
		)
		(fp_line
			(start 0.120396 0.2794)
			(end -0.12065 0.2794)
			(stroke
				(width 0.1)
				(type default)
			)
			(layer "F.Fab")
		)
		(fp_line
			(start -0.12065 -0.2794)
			(end 0.12065 -0.2794)
			(stroke
				(width 0.1)
				(type default)
			)
			(layer "F.Fab")
		)
		(fp_line
			(start 0.12065 -0.2794)
			(end 0.12065 -0.3048)
			(stroke
				(width 0.1)
				(type default)
			)
			(layer "F.Fab")
		)
		(fp_line
			(start 0.12065 -0.3048)
			(end 0.67945 -0.3048)
			(stroke
				(width 0.1)
				(type default)
			)
			(layer "F.Fab")
		)
		(fp_line
			(start 0.67945 -0.3048)
			(end 0.67945 0.3048)
			(stroke
				(width 0.1)
				(type default)
			)
			(layer "F.Fab")
		)
		(fp_line
			(start -0.67945 -0.305054)
			(end -0.12065 -0.305054)
			(stroke
				(width 0.1)
				(type default)
			)
			(layer "F.Fab")
		)
		(fp_line
			(start -0.12065 -0.305054)
			(end -0.12065 -0.2794)
			(stroke
				(width 0.1)
				(type default)
			)
			(layer "F.Fab")
		)
		(pad "1" smd circle
			(at -0.40005 0 270)
			(size 0 0)
			(layers "F.Cu" "F.Mask" "F.Paste")
			(net "VSENSE_P3V3_INA230_2_INP")
		)
		(pad "2" smd circle
			(at 0.40005 0 270)
			(size 0 0)
			(layers "F.Cu" "F.Mask" "F.Paste")
			(net "VSENSE_P3V3_INA230_2_INN")
		)
	)
	(footprint ""
		(layer "F.Cu")
		(at 12.982956 -92.687648 90)
		(property "Reference" "R3660"
			(at 0 0 90)
			(layer "F.SilkS")
			(hide yes)
			(effects
				(font
					(size 1.27 1.27)
				)
			)
		)
		(property "Value" ""
			(at 0 0 90)
			(layer "F.Fab")
			(effects
				(font
					(size 1.27 1.27)
				)
			)
		)
		(duplicate_pad_numbers_are_jumpers no)
		(fp_line
			(start 0.7874 -0.4064)
			(end 0.7874 0.4064)
			(stroke
				(width 0.1524)
				(type default)
			)
			(layer "F.SilkS")
		)
		(fp_line
			(start -0.7874 -0.4064)
			(end 0.7874 -0.4064)
			(stroke
				(width 0.1524)
				(type default)
			)
			(layer "F.SilkS")
		)
		(fp_line
			(start 0.7874 0.4064)
			(end -0.7874 0.4064)
			(stroke
				(width 0.1524)
				(type default)
			)
			(layer "F.SilkS")
		)
		(fp_line
			(start -0.7874 0.4064)
			(end -0.7874 -0.4064)
			(stroke
				(width 0.1524)
				(type default)
			)
			(layer "F.SilkS")
		)
		(fp_line
			(start -0.12065 -0.305054)
			(end -0.12065 -0.2794)
			(stroke
				(width 0.1)
				(type default)
			)
			(layer "F.Fab")
		)
		(fp_line
			(start -0.67945 -0.305054)
			(end -0.12065 -0.305054)
			(stroke
				(width 0.1)
				(type default)
			)
			(layer "F.Fab")
		)
		(fp_line
			(start 0.67945 -0.3048)
			(end 0.67945 0.3048)
			(stroke
				(width 0.1)
				(type default)
			)
			(layer "F.Fab")
		)
		(fp_line
			(start 0.12065 -0.3048)
			(end 0.67945 -0.3048)
			(stroke
				(width 0.1)
				(type default)
			)
			(layer "F.Fab")
		)
		(fp_line
			(start 0.12065 -0.2794)
			(end 0.12065 -0.3048)
			(stroke
				(width 0.1)
				(type default)
			)
			(layer "F.Fab")
		)
		(fp_line
			(start -0.12065 -0.2794)
			(end 0.12065 -0.2794)
			(stroke
				(width 0.1)
				(type default)
			)
			(layer "F.Fab")
		)
		(fp_line
			(start 0.120396 0.2794)
			(end -0.12065 0.2794)
			(stroke
				(width 0.1)
				(type default)
			)
			(layer "F.Fab")
		)
		(fp_line
			(start -0.12065 0.2794)
			(end -0.12065 0.3048)
			(stroke
				(width 0.1)
				(type default)
			)
			(layer "F.Fab")
		)
		(fp_line
			(start 0.67945 0.3048)
			(end 0.120396 0.3048)
			(stroke
				(width 0.1)
				(type default)
			)
			(layer "F.Fab")
		)
		(fp_line
			(start 0.120396 0.3048)
			(end 0.120396 0.2794)
			(stroke
				(width 0.1)
				(type default)
			)
			(layer "F.Fab")
		)
		(fp_line
			(start -0.12065 0.3048)
			(end -0.67945 0.3048)
			(stroke
				(width 0.1)
				(type default)
			)
			(layer "F.Fab")
		)
		(fp_line
			(start -0.67945 0.3048)
			(end -0.67945 -0.305054)
			(stroke
				(width 0.1)
				(type default)
			)
			(layer "F.Fab")
		)
		(pad "1" smd circle
			(at -0.40005 0 90)
			(size 0 0)
			(layers "F.Cu" "F.Mask" "F.Paste")
			(net "P3V3_AUX")
		)
		(pad "2" smd circle
			(at 0.40005 0 90)
			(size 0 0)
			(layers "F.Cu" "F.Mask" "F.Paste")
			(net "RST_USB_HUB_R_N")
		)
	)
	(footprint ""
		(layer "F.Cu")
		(at 329.282044 -138.893042 90)
		(property "Reference" "PC259"
			(at 0 0 90)
			(layer "F.SilkS")
			(hide yes)
			(effects
				(font
					(size 1.27 1.27)
				)
			)
		)
		(property "Value" ""
			(at 0 0 90)
			(layer "F.Fab")
			(effects
				(font
					(size 1.27 1.27)
				)
			)
		)
		(duplicate_pad_numbers_are_jumpers no)
		(fp_line
			(start 0.7874 -0.4064)
			(end 0.7874 0.4064)
			(stroke
				(width 0.1524)
				(type default)
			)
			(layer "F.SilkS")
		)
		(fp_line
			(start -0.7874 -0.4064)
			(end 0.7874 -0.4064)
			(stroke
				(width 0.1524)
				(type default)
			)
			(layer "F.SilkS")
		)
		(fp_line
			(start 0.7874 0.4064)
			(end -0.7874 0.4064)
			(stroke
				(width 0.1524)
				(type default)
			)
			(layer "F.SilkS")
		)
		(fp_line
			(start -0.7874 0.4064)
			(end -0.7874 -0.4064)
			(stroke
				(width 0.1524)
				(type default)
			)
			(layer "F.SilkS")
		)
		(fp_line
			(start -0.12065 -0.305054)
			(end -0.12065 -0.2794)
			(stroke
				(width 0.1)
				(type default)
			)
			(layer "F.Fab")
		)
		(fp_line
			(start -0.67945 -0.305054)
			(end -0.12065 -0.305054)
			(stroke
				(width 0.1)
				(type default)
			)
			(layer "F.Fab")
		)
		(fp_line
			(start 0.67945 -0.3048)
			(end 0.67945 0.3048)
			(stroke
				(width 0.1)
				(type default)
			)
			(layer "F.Fab")
		)
		(fp_line
			(start 0.12065 -0.3048)
			(end 0.67945 -0.3048)
			(stroke
				(width 0.1)
				(type default)
			)
			(layer "F.Fab")
		)
		(fp_line
			(start 0.12065 -0.2794)
			(end 0.12065 -0.3048)
			(stroke
				(width 0.1)
				(type default)
			)
			(layer "F.Fab")
		)
		(fp_line
			(start -0.12065 -0.2794)
			(end 0.12065 -0.2794)
			(stroke
				(width 0.1)
				(type default)
			)
			(layer "F.Fab")
		)
		(fp_line
			(start 0.120396 0.2794)
			(end -0.12065 0.2794)
			(stroke
				(width 0.1)
				(type default)
			)
			(layer "F.Fab")
		)
		(fp_line
			(start -0.12065 0.2794)
			(end -0.12065 0.3048)
			(stroke
				(width 0.1)
				(type default)
			)
			(layer "F.Fab")
		)
		(fp_line
			(start 0.67945 0.3048)
			(end 0.120396 0.3048)
			(stroke
				(width 0.1)
				(type default)
			)
			(layer "F.Fab")
		)
		(fp_line
			(start 0.120396 0.3048)
			(end 0.120396 0.2794)
			(stroke
				(width 0.1)
				(type default)
			)
			(layer "F.Fab")
		)
		(fp_line
			(start -0.12065 0.3048)
			(end -0.67945 0.3048)
			(stroke
				(width 0.1)
				(type default)
			)
			(layer "F.Fab")
		)
		(fp_line
			(start -0.67945 0.3048)
			(end -0.67945 -0.305054)
			(stroke
				(width 0.1)
				(type default)
			)
			(layer "F.Fab")
		)
		(pad "1" smd circle
			(at -0.40005 0 90)
			(size 0 0)
			(layers "F.Cu" "F.Mask" "F.Paste")
			(net "PVDD18_S5_P0_FB")
		)
		(pad "2" smd circle
			(at 0.40005 0 90)
			(size 0 0)
			(layers "F.Cu" "F.Mask" "F.Paste")
			(net "PVDD18_S5_P0_FB_RC")
		)
	)
)
